(kicad_pcb
	(version 20260206)
	(generator "pcbnew")
	(generator_version "10.0")
	(general
		(thickness 1.6)
		(legacy_teardrops no)
	)
	(paper "A4")
	(title_block
		(title "01162023_DA0F0TEBIF0_F0T_Expander_BD_F_brd_V02_OCP.brd")
		(comment 1 "Grand Teton / footprints 9700-9705 of 9728")
	)
	(layers
		(0 "F.Cu" signal "TOP")
		(4 "In1.Cu" signal "GND")
		(6 "In2.Cu" signal "VCC")
		(8 "In3.Cu" signal "VCC1")
		(10 "In4.Cu" signal "GND1")
		(12 "In5.Cu" signal "IN1")
		(14 "In6.Cu" signal "GND2")
		(16 "In7.Cu" signal "IN2")
		(18 "In8.Cu" signal "GND3")
		(20 "In9.Cu" signal "IN3")
		(22 "In10.Cu" signal "GND4")
		(24 "In11.Cu" signal "IN4")
		(26 "In12.Cu" signal "GND5")
		(28 "In13.Cu" signal "IN5")
		(30 "In14.Cu" signal "GND6")
		(32 "In15.Cu" signal "IN6")
		(34 "In16.Cu" signal "GND7")
		(2 "B.Cu" signal "BOTTOM")
		(9 "F.Adhes" user "F.Adhesive")
		(11 "B.Adhes" user "B.Adhesive")
		(13 "F.Paste" user "Package Geometry/Pastemask Top")
		(15 "B.Paste" user "Package Geometry/Pastemask Bottom")
		(5 "F.SilkS" user "Ref Des/Silkscreen Top")
		(7 "B.SilkS" user "Ref Des/Silkscreen Bottom")
		(1 "F.Mask" user "Board Geometry/Soldermask Top")
		(3 "B.Mask" user "Board Geometry/Soldermask Bottom")
		(17 "Dwgs.User" user "User.Drawings")
		(19 "Cmts.User" user "User.Comments")
		(21 "Eco1.User" user "User.Eco1")
		(23 "Eco2.User" user "User.Eco2")
		(25 "Edge.Cuts" user "Board Geometry/Outline")
		(27 "Margin" user)
		(31 "F.CrtYd" user "Package Geometry/Place Bound Top")
		(29 "B.CrtYd" user "Package Geometry/Place Bound Bottom")
		(35 "F.Fab" user "Ref Des/Assembly Top")
		(33 "B.Fab" user "Ref Des/Assembly Bottom")
	)
	(footprint ""
		(layer "B.Cu")
		(at 63.375286 -109.481366 180)
		(property "Reference" "R83"
			(at 0 0 0)
			(layer "B.SilkS")
			(hide yes)
			(effects
				(font
					(size 1.27 1.27)
				)
				(justify mirror)
			)
		)
		(property "Value" ""
			(at 0 0 0)
			(layer "B.Fab")
			(effects
				(font
					(size 1.27 1.27)
				)
				(justify mirror)
			)
		)
		(duplicate_pad_numbers_are_jumpers no)
		(fp_line
			(start 0.7874 0.4064)
			(end 0.7874 -0.4064)
			(stroke
				(width 0.1524)
				(type default)
			)
			(layer "B.SilkS")
		)
		(fp_line
			(start 0.7874 -0.4064)
			(end -0.7874 -0.4064)
			(stroke
				(width 0.1524)
				(type default)
			)
			(layer "B.SilkS")
		)
		(fp_line
			(start -0.7874 0.4064)
			(end 0.7874 0.4064)
			(stroke
				(width 0.1524)
				(type default)
			)
			(layer "B.SilkS")
		)
		(fp_line
			(start -0.7874 -0.4064)
			(end -0.7874 0.4064)
			(stroke
				(width 0.1524)
				(type default)
			)
			(layer "B.SilkS")
		)
		(fp_line
			(start 0.67945 0.3048)
			(end 0.67945 -0.305054)
			(stroke
				(width 0.1)
				(type default)
			)
			(layer "B.Fab")
		)
		(fp_line
			(start 0.67945 -0.305054)
			(end 0.12065 -0.305054)
			(stroke
				(width 0.1)
				(type default)
			)
			(layer "B.Fab")
		)
		(fp_line
			(start 0.12065 0.3048)
			(end 0.67945 0.3048)
			(stroke
				(width 0.1)
				(type default)
			)
			(layer "B.Fab")
		)
		(fp_line
			(start 0.12065 0.2794)
			(end 0.12065 0.3048)
			(stroke
				(width 0.1)
				(type default)
			)
			(layer "B.Fab")
		)
		(fp_line
			(start 0.12065 -0.2794)
			(end -0.12065 -0.2794)
			(stroke
				(width 0.1)
				(type default)
			)
			(layer "B.Fab")
		)
		(fp_line
			(start 0.12065 -0.305054)
			(end 0.12065 -0.2794)
			(stroke
				(width 0.1)
				(type default)
			)
			(layer "B.Fab")
		)
		(fp_line
			(start -0.120396 0.3048)
			(end -0.120396 0.2794)
			(stroke
				(width 0.1)
				(type default)
			)
			(layer "B.Fab")
		)
		(fp_line
			(start -0.120396 0.2794)
			(end 0.12065 0.2794)
			(stroke
				(width 0.1)
				(type default)
			)
			(layer "B.Fab")
		)
		(fp_line
			(start -0.12065 -0.2794)
			(end -0.12065 -0.3048)
			(stroke
				(width 0.1)
				(type default)
			)
			(layer "B.Fab")
		)
		(fp_line
			(start -0.12065 -0.3048)
			(end -0.67945 -0.3048)
			(stroke
				(width 0.1)
				(type default)
			)
			(layer "B.Fab")
		)
		(fp_line
			(start -0.67945 0.3048)
			(end -0.120396 0.3048)
			(stroke
				(width 0.1)
				(type default)
			)
			(layer "B.Fab")
		)
		(fp_line
			(start -0.67945 -0.3048)
			(end -0.67945 0.3048)
			(stroke
				(width 0.1)
				(type default)
			)
			(layer "B.Fab")
		)
		(pad "1" smd circle
			(at 0.40005 0)
			(size 0 0)
			(layers "B.Cu" "B.Mask" "B.Paste")
			(net "NIC1_BIF1_N")
		)
		(pad "2" smd circle
			(at -0.40005 0)
			(size 0 0)
			(layers "B.Cu" "B.Mask" "B.Paste")
			(net "GND")
		)
	)
	(footprint ""
		(layer "B.Cu")
		(at 353.66833 -219.158566 180)
		(property "Reference" "C2044"
			(at 0 0 0)
			(layer "B.SilkS")
			(hide yes)
			(effects
				(font
					(size 1.27 1.27)
				)
				(justify mirror)
			)
		)
		(property "Value" ""
			(at 0 0 0)
			(layer "B.Fab")
			(effects
				(font
					(size 1.27 1.27)
				)
				(justify mirror)
			)
		)
		(duplicate_pad_numbers_are_jumpers no)
		(fp_line
			(start 0.69215 0.2921)
			(end 0.69215 -0.2921)
			(stroke
				(width 0.1524)
				(type default)
			)
			(layer "B.SilkS")
		)
		(fp_line
			(start 0.69215 -0.2921)
			(end -0.69215 -0.2921)
			(stroke
				(width 0.1524)
				(type default)
			)
			(layer "B.SilkS")
		)
		(fp_line
			(start -0.69215 0.2921)
			(end 0.69215 0.2921)
			(stroke
				(width 0.1524)
				(type default)
			)
			(layer "B.SilkS")
		)
		(fp_line
			(start -0.69215 -0.2921)
			(end -0.69215 0.2921)
			(stroke
				(width 0.1524)
				(type default)
			)
			(layer "B.SilkS")
		)
		(fp_line
			(start 0.51435 0.2794)
			(end 0.51435 -0.2794)
			(stroke
				(width 0.1)
				(type default)
			)
			(layer "B.Fab")
		)
		(fp_line
			(start 0.51435 -0.2794)
			(end -0.51435 -0.2794)
			(stroke
				(width 0.1)
				(type default)
			)
			(layer "B.Fab")
		)
		(fp_line
			(start -0.51435 0.2794)
			(end 0.51435 0.2794)
			(stroke
				(width 0.1)
				(type default)
			)
			(layer "B.Fab")
		)
		(fp_line
			(start -0.51435 -0.2794)
			(end -0.51435 0.2794)
			(stroke
				(width 0.1)
				(type default)
			)
			(layer "B.Fab")
		)
		(pad "1" smd circle
			(at 0.40005 0)
			(size 0 0)
			(layers "B.Cu" "B.Mask" "B.Paste")
			(net "P3V3_FPGA_VCCIO1")
		)
		(pad "2" smd circle
			(at -0.40005 0)
			(size 0 0)
			(layers "B.Cu" "B.Mask" "B.Paste")
			(net "GND")
		)
		(zone
			(layer "B.Cu")
			(hatch none 0.5)
			(connect_pads
				(clearance 0)
			)
			(min_thickness 0.25)
			(keepout
				(tracks not_allowed)
				(vias allowed)
				(pads allowed)
				(copperpour not_allowed)
				(footprints allowed)
			)
			(placement
				(enabled no)
				(sheetname "")
			)
			(fill
				(thermal_gap 0.5)
				(thermal_bridge_width 0.5)
				(island_removal_mode 0)
			)
			(polygon
				(pts
					(xy 353.47783 -219.246196) (xy 353.56927 -219.304362) (xy 353.76866 -219.304362) (xy 353.85883 -219.246196)
					(xy 353.85883 -219.070936) (xy 353.76866 -219.012516) (xy 353.56927 -219.012516) (xy 353.47783 -219.070682)
				)
			)
		)
	)
	(footprint ""
		(layer "B.Cu")
		(at 130.893058 -228.981)
		(property "Reference" "R3466"
			(at 0 0 0)
			(layer "B.SilkS")
			(hide yes)
			(effects
				(font
					(size 1.27 1.27)
				)
				(justify mirror)
			)
		)
		(property "Value" ""
			(at 0 0 0)
			(layer "B.Fab")
			(effects
				(font
					(size 1.27 1.27)
				)
				(justify mirror)
			)
		)
		(duplicate_pad_numbers_are_jumpers no)
		(fp_line
			(start -0.7874 -0.4064)
			(end -0.7874 0.4064)
			(stroke
				(width 0.1524)
				(type default)
			)
			(layer "B.SilkS")
		)
		(fp_line
			(start -0.7874 0.4064)
			(end 0.7874 0.4064)
			(stroke
				(width 0.1524)
				(type default)
			)
			(layer "B.SilkS")
		)
		(fp_line
			(start 0.7874 -0.4064)
			(end -0.7874 -0.4064)
			(stroke
				(width 0.1524)
				(type default)
			)
			(layer "B.SilkS")
		)
		(fp_line
			(start 0.7874 0.4064)
			(end 0.7874 -0.4064)
			(stroke
				(width 0.1524)
				(type default)
			)
			(layer "B.SilkS")
		)
		(fp_line
			(start -0.67945 -0.3048)
			(end -0.67945 0.3048)
			(stroke
				(width 0.1)
				(type default)
			)
			(layer "B.Fab")
		)
		(fp_line
			(start -0.67945 0.3048)
			(end -0.120396 0.3048)
			(stroke
				(width 0.1)
				(type default)
			)
			(layer "B.Fab")
		)
		(fp_line
			(start -0.12065 -0.3048)
			(end -0.67945 -0.3048)
			(stroke
				(width 0.1)
				(type default)
			)
			(layer "B.Fab")
		)
		(fp_line
			(start -0.12065 -0.2794)
			(end -0.12065 -0.3048)
			(stroke
				(width 0.1)
				(type default)
			)
			(layer "B.Fab")
		)
		(fp_line
			(start -0.120396 0.2794)
			(end 0.12065 0.2794)
			(stroke
				(width 0.1)
				(type default)
			)
			(layer "B.Fab")
		)
		(fp_line
			(start -0.120396 0.3048)
			(end -0.120396 0.2794)
			(stroke
				(width 0.1)
				(type default)
			)
			(layer "B.Fab")
		)
		(fp_line
			(start 0.12065 -0.305054)
			(end 0.12065 -0.2794)
			(stroke
				(width 0.1)
				(type default)
			)
			(layer "B.Fab")
		)
		(fp_line
			(start 0.12065 -0.2794)
			(end -0.12065 -0.2794)
			(stroke
				(width 0.1)
				(type default)
			)
			(layer "B.Fab")
		)
		(fp_line
			(start 0.12065 0.2794)
			(end 0.12065 0.3048)
			(stroke
				(width 0.1)
				(type default)
			)
			(layer "B.Fab")
		)
		(fp_line
			(start 0.12065 0.3048)
			(end 0.67945 0.3048)
			(stroke
				(width 0.1)
				(type default)
			)
			(layer "B.Fab")
		)
		(fp_line
			(start 0.67945 -0.305054)
			(end 0.12065 -0.305054)
			(stroke
				(width 0.1)
				(type default)
			)
			(layer "B.Fab")
		)
		(fp_line
			(start 0.67945 0.3048)
			(end 0.67945 -0.305054)
			(stroke
				(width 0.1)
				(type default)
			)
			(layer "B.Fab")
		)
		(pad "1" smd circle
			(at 0.40005 0 180)
			(size 0 0)
			(layers "B.Cu" "B.Mask" "B.Paste")
			(net "P1V8_PEX")
		)
		(pad "2" smd circle
			(at -0.40005 0 180)
			(size 0 0)
			(layers "B.Cu" "B.Mask" "B.Paste")
			(net "SPI_PEX1_SDIO2_R1")
		)
	)
	(footprint ""
		(layer "B.Cu")
		(at 282.843986 -138.421618 180)
		(property "Reference" "R228"
			(at 0 0 0)
			(layer "B.SilkS")
			(hide yes)
			(effects
				(font
					(size 1.27 1.27)
				)
				(justify mirror)
			)
		)
		(property "Value" ""
			(at 0 0 0)
			(layer "B.Fab")
			(effects
				(font
					(size 1.27 1.27)
				)
				(justify mirror)
			)
		)
		(duplicate_pad_numbers_are_jumpers no)
		(fp_line
			(start 0.7874 0.4064)
			(end 0.7874 -0.4064)
			(stroke
				(width 0.1524)
				(type default)
			)
			(layer "B.SilkS")
		)
		(fp_line
			(start 0.7874 -0.4064)
			(end -0.7874 -0.4064)
			(stroke
				(width 0.1524)
				(type default)
			)
			(layer "B.SilkS")
		)
		(fp_line
			(start -0.7874 0.4064)
			(end 0.7874 0.4064)
			(stroke
				(width 0.1524)
				(type default)
			)
			(layer "B.SilkS")
		)
		(fp_line
			(start -0.7874 -0.4064)
			(end -0.7874 0.4064)
			(stroke
				(width 0.1524)
				(type default)
			)
			(layer "B.SilkS")
		)
		(fp_line
			(start 0.67945 0.3048)
			(end 0.67945 -0.305054)
			(stroke
				(width 0.1)
				(type default)
			)
			(layer "B.Fab")
		)
		(fp_line
			(start 0.67945 -0.305054)
			(end 0.12065 -0.305054)
			(stroke
				(width 0.1)
				(type default)
			)
			(layer "B.Fab")
		)
		(fp_line
			(start 0.12065 0.3048)
			(end 0.67945 0.3048)
			(stroke
				(width 0.1)
				(type default)
			)
			(layer "B.Fab")
		)
		(fp_line
			(start 0.12065 0.2794)
			(end 0.12065 0.3048)
			(stroke
				(width 0.1)
				(type default)
			)
			(layer "B.Fab")
		)
		(fp_line
			(start 0.12065 -0.2794)
			(end -0.12065 -0.2794)
			(stroke
				(width 0.1)
				(type default)
			)
			(layer "B.Fab")
		)
		(fp_line
			(start 0.12065 -0.305054)
			(end 0.12065 -0.2794)
			(stroke
				(width 0.1)
				(type default)
			)
			(layer "B.Fab")
		)
		(fp_line
			(start -0.120396 0.3048)
			(end -0.120396 0.2794)
			(stroke
				(width 0.1)
				(type default)
			)
			(layer "B.Fab")
		)
		(fp_line
			(start -0.120396 0.2794)
			(end 0.12065 0.2794)
			(stroke
				(width 0.1)
				(type default)
			)
			(layer "B.Fab")
		)
		(fp_line
			(start -0.12065 -0.2794)
			(end -0.12065 -0.3048)
			(stroke
				(width 0.1)
				(type default)
			)
			(layer "B.Fab")
		)
		(fp_line
			(start -0.12065 -0.3048)
			(end -0.67945 -0.3048)
			(stroke
				(width 0.1)
				(type default)
			)
			(layer "B.Fab")
		)
		(fp_line
			(start -0.67945 0.3048)
			(end -0.120396 0.3048)
			(stroke
				(width 0.1)
				(type default)
			)
			(layer "B.Fab")
		)
		(fp_line
			(start -0.67945 -0.3048)
			(end -0.67945 0.3048)
			(stroke
				(width 0.1)
				(type default)
			)
			(layer "B.Fab")
		)
		(pad "1" smd circle
			(at 0.40005 0)
			(size 0 0)
			(layers "B.Cu" "B.Mask" "B.Paste")
			(net "NIC4_AUX_PWR_EN")
		)
		(pad "2" smd circle
			(at -0.40005 0)
			(size 0 0)
			(layers "B.Cu" "B.Mask" "B.Paste")
			(net "GND")
		)
	)
	(footprint ""
		(layer "B.Cu")
		(at 210.228942 -259.311648 90)
		(property "Reference" "R6348"
			(at 0 0 90)
			(layer "B.SilkS")
			(hide yes)
			(effects
				(font
					(size 1.27 1.27)
				)
				(justify mirror)
			)
		)
		(property "Value" ""
			(at 0 0 90)
			(layer "B.Fab")
			(effects
				(font
					(size 1.27 1.27)
				)
				(justify mirror)
			)
		)
		(duplicate_pad_numbers_are_jumpers no)
		(fp_line
			(start 0.7874 -0.4064)
			(end -0.7874 -0.4064)
			(stroke
				(width 0.1524)
				(type default)
			)
			(layer "B.SilkS")
		)
		(fp_line
			(start -0.7874 -0.4064)
			(end -0.7874 0.4064)
			(stroke
				(width 0.1524)
				(type default)
			)
			(layer "B.SilkS")
		)
		(fp_line
			(start 0.7874 0.4064)
			(end 0.7874 -0.4064)
			(stroke
				(width 0.1524)
				(type default)
			)
			(layer "B.SilkS")
		)
		(fp_line
			(start -0.7874 0.4064)
			(end 0.7874 0.4064)
			(stroke
				(width 0.1524)
				(type default)
			)
			(layer "B.SilkS")
		)
		(fp_line
			(start 0.67945 -0.305054)
			(end 0.12065 -0.305054)
			(stroke
				(width 0.1)
				(type default)
			)
			(layer "B.Fab")
		)
		(fp_line
			(start 0.12065 -0.305054)
			(end 0.12065 -0.2794)
			(stroke
				(width 0.1)
				(type default)
			)
			(layer "B.Fab")
		)
		(fp_line
			(start -0.12065 -0.3048)
			(end -0.67945 -0.3048)
			(stroke
				(width 0.1)
				(type default)
			)
			(layer "B.Fab")
		)
		(fp_line
			(start -0.67945 -0.3048)
			(end -0.67945 0.3048)
			(stroke
				(width 0.1)
				(type default)
			)
			(layer "B.Fab")
		)
		(fp_line
			(start 0.12065 -0.2794)
			(end -0.12065 -0.2794)
			(stroke
				(width 0.1)
				(type default)
			)
			(layer "B.Fab")
		)
		(fp_line
			(start -0.12065 -0.2794)
			(end -0.12065 -0.3048)
			(stroke
				(width 0.1)
				(type default)
			)
			(layer "B.Fab")
		)
		(fp_line
			(start 0.12065 0.2794)
			(end 0.12065 0.3048)
			(stroke
				(width 0.1)
				(type default)
			)
			(layer "B.Fab")
		)
		(fp_line
			(start -0.120396 0.2794)
			(end 0.12065 0.2794)
			(stroke
				(width 0.1)
				(type default)
			)
			(layer "B.Fab")
		)
		(fp_line
			(start 0.67945 0.3048)
			(end 0.67945 -0.305054)
			(stroke
				(width 0.1)
				(type default)
			)
			(layer "B.Fab")
		)
		(fp_line
			(start 0.12065 0.3048)
			(end 0.67945 0.3048)
			(stroke
				(width 0.1)
				(type default)
			)
			(layer "B.Fab")
		)
		(fp_line
			(start -0.120396 0.3048)
			(end -0.120396 0.2794)
			(stroke
				(width 0.1)
				(type default)
			)
			(layer "B.Fab")
		)
		(fp_line
			(start -0.67945 0.3048)
			(end -0.120396 0.3048)
			(stroke
				(width 0.1)
				(type default)
			)
			(layer "B.Fab")
		)
		(pad "1" smd circle
			(at 0.40005 0 270)
			(size 0 0)
			(layers "B.Cu" "B.Mask" "B.Paste")
			(net "P1V8_PEX")
		)
		(pad "2" smd circle
			(at -0.40005 0 270)
			(size 0 0)
			(layers "B.Cu" "B.Mask" "B.Paste")
			(net "SMB_PEX3_MUX_SDA")
		)
	)
	(footprint ""
		(layer "B.Cu")
		(at 203.474828 -368.951764 -90)
		(property "Reference" "PC4"
			(at 0 0 90)
			(layer "B.SilkS")
			(hide yes)
			(effects
				(font
					(size 1.27 1.27)
				)
				(justify mirror)
			)
		)
		(property "Value" ""
			(at 0 0 90)
			(layer "B.Fab")
			(effects
				(font
					(size 1.27 1.27)
				)
				(justify mirror)
			)
		)
		(duplicate_pad_numbers_are_jumpers no)
		(fp_line
			(start -0.7874 0.4064)
			(end 0.7874 0.4064)
			(stroke
				(width 0.1524)
				(type default)
			)
			(layer "B.SilkS")
		)
		(fp_line
			(start 0.7874 0.4064)
			(end 0.7874 -0.4064)
			(stroke
				(width 0.1524)
				(type default)
			)
			(layer "B.SilkS")
		)
		(fp_line
			(start -0.7874 -0.4064)
			(end -0.7874 0.4064)
			(stroke
				(width 0.1524)
				(type default)
			)
			(layer "B.SilkS")
		)
		(fp_line
			(start 0.7874 -0.4064)
			(end -0.7874 -0.4064)
			(stroke
				(width 0.1524)
				(type default)
			)
			(layer "B.SilkS")
		)
		(fp_line
			(start -0.67945 0.3048)
			(end -0.120396 0.3048)
			(stroke
				(width 0.1)
				(type default)
			)
			(layer "B.Fab")
		)
		(fp_line
			(start -0.120396 0.3048)
			(end -0.120396 0.2794)
			(stroke
				(width 0.1)
				(type default)
			)
			(layer "B.Fab")
		)
		(fp_line
			(start 0.12065 0.3048)
			(end 0.67945 0.3048)
			(stroke
				(width 0.1)
				(type default)
			)
			(layer "B.Fab")
		)
		(fp_line
			(start 0.67945 0.3048)
			(end 0.67945 -0.305054)
			(stroke
				(width 0.1)
				(type default)
			)
			(layer "B.Fab")
		)
		(fp_line
			(start -0.120396 0.2794)
			(end 0.12065 0.2794)
			(stroke
				(width 0.1)
				(type default)
			)
			(layer "B.Fab")
		)
		(fp_line
			(start 0.12065 0.2794)
			(end 0.12065 0.3048)
			(stroke
				(width 0.1)
				(type default)
			)
			(layer "B.Fab")
		)
		(fp_line
			(start -0.12065 -0.2794)
			(end -0.12065 -0.3048)
			(stroke
				(width 0.1)
				(type default)
			)
			(layer "B.Fab")
		)
		(fp_line
			(start 0.12065 -0.2794)
			(end -0.12065 -0.2794)
			(stroke
				(width 0.1)
				(type default)
			)
			(layer "B.Fab")
		)
		(fp_line
			(start -0.67945 -0.3048)
			(end -0.67945 0.3048)
			(stroke
				(width 0.1)
				(type default)
			)
			(layer "B.Fab")
		)
		(fp_line
			(start -0.12065 -0.3048)
			(end -0.67945 -0.3048)
			(stroke
				(width 0.1)
				(type default)
			)
			(layer "B.Fab")
		)
		(fp_line
			(start 0.12065 -0.305054)
			(end 0.12065 -0.2794)
			(stroke
				(width 0.1)
				(type default)
			)
			(layer "B.Fab")
		)
		(fp_line
			(start 0.67945 -0.305054)
			(end 0.12065 -0.305054)
			(stroke
				(width 0.1)
				(type default)
			)
			(layer "B.Fab")
		)
		(pad "1" smd circle
			(at 0.40005 0 90)
			(size 0 0)
			(layers "B.Cu" "B.Mask" "B.Paste")
			(net "HSC_VDD_R")
		)
		(pad "2" smd circle
			(at -0.40005 0 90)
			(size 0 0)
			(layers "B.Cu" "B.Mask" "B.Paste")
			(net "AGND_HSC")
		)
	)
)
